# S9S_MB_2U (Grand Teton) — schematic netlist excerpt (pin names and nets, part order shuffled) for the footprints in the layout excerpt that follows; sources: Cadence DE-HDL packaged netlist, KiCad conversion of 03242023_DA0F0TMBIJ0_F0T_Motherboard_J_brd_V01_OCP.brd

R838  Q_RES  0 5% CHIP  pkg 0402LF  page 129 : A = RST_PLD_CPU0_DRAM_EF_N ; B = RST_M_EF_CPU0_FPGA_N
C1940  Q_CAP  10UF 6.3V 20% X6S  pkg C0402  page 217 : A = P3V3_AUX_FPGA_VCCIO5 ; B = GND

(kicad_pcb
	(version 20260206)
	(generator "pcbnew")
	(generator_version "10.0")
	(general
		(thickness 1.6)
		(legacy_teardrops no)
	)
	(paper "A4")
	(title_block
		(title "03242023_DA0F0TMBIJ0_F0T_Motherboard_J_brd_V01_OCP.brd")
		(comment 1 "Grand Teton / footprints 4354-4355 of 6105")
	)
	(layers
		(0 "F.Cu" signal "TOP")
		(4 "In1.Cu" signal "GND")
		(6 "In2.Cu" signal "IN1")
		(8 "In3.Cu" signal "GND1")
		(10 "In4.Cu" signal "IN2")
		(12 "In5.Cu" signal "GND2")
		(14 "In6.Cu" signal "IN3")
		(16 "In7.Cu" signal "GND3")
		(18 "In8.Cu" signal "VCC")
		(20 "In9.Cu" signal "VCC1")
		(22 "In10.Cu" signal "GND4")
		(24 "In11.Cu" signal "IN4")
		(26 "In12.Cu" signal "GND5")
		(28 "In13.Cu" signal "IN5")
		(30 "In14.Cu" signal "GND6")
		(32 "In15.Cu" signal "IN6")
		(34 "In16.Cu" signal "GND7")
		(2 "B.Cu" signal "BOTTOM")
		(9 "F.Adhes" user "F.Adhesive")
		(11 "B.Adhes" user "B.Adhesive")
		(13 "F.Paste" user "Package Geometry/Pastemask Top")
		(15 "B.Paste" user "Package Geometry/Pastemask Bottom")
		(5 "F.SilkS" user "Ref Des/Silkscreen Top")
		(7 "B.SilkS" user "Ref Des/Silkscreen Bottom")
		(1 "F.Mask" user "Board Geometry/Soldermask Top")
		(3 "B.Mask" user "Board Geometry/Soldermask Bottom")
		(17 "Dwgs.User" user "User.Drawings")
		(19 "Cmts.User" user "User.Comments")
		(21 "Eco1.User" user "User.Eco1")
		(23 "Eco2.User" user "User.Eco2")
		(25 "Edge.Cuts" user "Board Geometry/Outline")
		(27 "Margin" user)
		(31 "F.CrtYd" user "Package Geometry/Place Bound Top")
		(29 "B.CrtYd" user "Package Geometry/Place Bound Bottom")
		(35 "F.Fab" user "Ref Des/Assembly Top")
		(33 "B.Fab" user "Ref Des/Assembly Bottom")
	)
	(footprint ""
		(layer "B.Cu")
		(at 422.314624 -193.353436 -90)
		(property "Reference" "R838"
			(at 0 0 90)
			(layer "B.SilkS")
			(hide yes)
			(effects
				(font
					(size 1.27 1.27)
				)
				(justify mirror)
			)
		)
		(property "Value" ""
			(at 0 0 90)
			(layer "B.Fab")
			(effects
				(font
					(size 1.27 1.27)
				)
				(justify mirror)
			)
		)
		(duplicate_pad_numbers_are_jumpers no)
		(fp_line
			(start -0.7874 0.4064)
			(end 0.7874 0.4064)
			(stroke
				(width 0.1524)
				(type default)
			)
			(layer "B.SilkS")
		)
		(fp_line
			(start 0.7874 0.4064)
			(end 0.7874 -0.4064)
			(stroke
				(width 0.1524)
				(type default)
			)
			(layer "B.SilkS")
		)
		(fp_line
			(start -0.7874 -0.4064)
			(end -0.7874 0.4064)
			(stroke
				(width 0.1524)
				(type default)
			)
			(layer "B.SilkS")
		)
		(fp_line
			(start 0.7874 -0.4064)
			(end -0.7874 -0.4064)
			(stroke
				(width 0.1524)
				(type default)
			)
			(layer "B.SilkS")
		)
		(fp_line
			(start -0.67945 0.3048)
			(end -0.120396 0.3048)
			(stroke
				(width 0.1)
				(type default)
			)
			(layer "B.Fab")
		)
		(fp_line
			(start -0.120396 0.3048)
			(end -0.120396 0.2794)
			(stroke
				(width 0.1)
				(type default)
			)
			(layer "B.Fab")
		)
		(fp_line
			(start 0.12065 0.3048)
			(end 0.67945 0.3048)
			(stroke
				(width 0.1)
				(type default)
			)
			(layer "B.Fab")
		)
		(fp_line
			(start 0.67945 0.3048)
			(end 0.67945 -0.305054)
			(stroke
				(width 0.1)
				(type default)
			)
			(layer "B.Fab")
		)
		(fp_line
			(start -0.120396 0.2794)
			(end 0.12065 0.2794)
			(stroke
				(width 0.1)
				(type default)
			)
			(layer "B.Fab")
		)
		(fp_line
			(start 0.12065 0.2794)
			(end 0.12065 0.3048)
			(stroke
				(width 0.1)
				(type default)
			)
			(layer "B.Fab")
		)
		(fp_line
			(start -0.12065 -0.2794)
			(end -0.12065 -0.3048)
			(stroke
				(width 0.1)
				(type default)
			)
			(layer "B.Fab")
		)
		(fp_line
			(start 0.12065 -0.2794)
			(end -0.12065 -0.2794)
			(stroke
				(width 0.1)
				(type default)
			)
			(layer "B.Fab")
		)
		(fp_line
			(start -0.67945 -0.3048)
			(end -0.67945 0.3048)
			(stroke
				(width 0.1)
				(type default)
			)
			(layer "B.Fab")
		)
		(fp_line
			(start -0.12065 -0.3048)
			(end -0.67945 -0.3048)
			(stroke
				(width 0.1)
				(type default)
			)
			(layer "B.Fab")
		)
		(fp_line
			(start 0.12065 -0.305054)
			(end 0.12065 -0.2794)
			(stroke
				(width 0.1)
				(type default)
			)
			(layer "B.Fab")
		)
		(fp_line
			(start 0.67945 -0.305054)
			(end 0.12065 -0.305054)
			(stroke
				(width 0.1)
				(type default)
			)
			(layer "B.Fab")
		)
		(pad "1" smd circle
			(at 0.40005 0 90)
			(size 0 0)
			(layers "B.Cu" "B.Mask" "B.Paste")
			(net "RST_PLD_CPU0_DRAM_EF_N")
		)
		(pad "2" smd circle
			(at -0.40005 0 90)
			(size 0 0)
			(layers "B.Cu" "B.Mask" "B.Paste")
			(net "RST_M_EF_CPU0_FPGA_N")
		)
	)
	(footprint ""
		(layer "B.Cu")
		(at 173.04893 -103.723948)
		(property "Reference" "C1940"
			(at 0 0 0)
			(layer "B.SilkS")
			(hide yes)
			(effects
				(font
					(size 1.27 1.27)
				)
				(justify mirror)
			)
		)
		(property "Value" ""
			(at 0 0 0)
			(layer "B.Fab")
			(effects
				(font
					(size 1.27 1.27)
				)
				(justify mirror)
			)
		)
		(duplicate_pad_numbers_are_jumpers no)
		(fp_line
			(start -0.7874 -0.4064)
			(end -0.7874 0.4064)
			(stroke
				(width 0.1524)
				(type default)
			)
			(layer "B.SilkS")
		)
		(fp_line
			(start -0.7874 0.4064)
			(end 0.7874 0.4064)
			(stroke
				(width 0.1524)
				(type default)
			)
			(layer "B.SilkS")
		)
		(fp_line
			(start 0.7874 -0.4064)
			(end -0.7874 -0.4064)
			(stroke
				(width 0.1524)
				(type default)
			)
			(layer "B.SilkS")
		)
		(fp_line
			(start 0.7874 0.4064)
			(end 0.7874 -0.4064)
			(stroke
				(width 0.1524)
				(type default)
			)
			(layer "B.SilkS")
		)
		(fp_line
			(start -0.67945 -0.3048)
			(end -0.67945 0.3048)
			(stroke
				(width 0.1)
				(type default)
			)
			(layer "B.Fab")
		)
		(fp_line
			(start -0.67945 0.3048)
			(end -0.120396 0.3048)
			(stroke
				(width 0.1)
				(type default)
			)
			(layer "B.Fab")
		)
		(fp_line
			(start -0.12065 -0.3048)
			(end -0.67945 -0.3048)
			(stroke
				(width 0.1)
				(type default)
			)
			(layer "B.Fab")
		)
		(fp_line
			(start -0.12065 -0.2794)
			(end -0.12065 -0.3048)
			(stroke
				(width 0.1)
				(type default)
			)
			(layer "B.Fab")
		)
		(fp_line
			(start -0.120396 0.2794)
			(end 0.12065 0.2794)
			(stroke
				(width 0.1)
				(type default)
			)
			(layer "B.Fab")
		)
		(fp_line
			(start -0.120396 0.3048)
			(end -0.120396 0.2794)
			(stroke
				(width 0.1)
				(type default)
			)
			(layer "B.Fab")
		)
		(fp_line
			(start 0.12065 -0.305054)
			(end 0.12065 -0.2794)
			(stroke
				(width 0.1)
				(type default)
			)
			(layer "B.Fab")
		)
		(fp_line
			(start 0.12065 -0.2794)
			(end -0.12065 -0.2794)
			(stroke
				(width 0.1)
				(type default)
			)
			(layer "B.Fab")
		)
		(fp_line
			(start 0.12065 0.2794)
			(end 0.12065 0.3048)
			(stroke
				(width 0.1)
				(type default)
			)
			(layer "B.Fab")
		)
		(fp_line
			(start 0.12065 0.3048)
			(end 0.67945 0.3048)
			(stroke
				(width 0.1)
				(type default)
			)
			(layer "B.Fab")
		)
		(fp_line
			(start 0.67945 -0.305054)
			(end 0.12065 -0.305054)
			(stroke
				(width 0.1)
				(type default)
			)
			(layer "B.Fab")
		)
		(fp_line
			(start 0.67945 0.3048)
			(end 0.67945 -0.305054)
			(stroke
				(width 0.1)
				(type default)
			)
			(layer "B.Fab")
		)
		(pad "1" smd circle
			(at 0.40005 0 180)
			(size 0 0)
			(layers "B.Cu" "B.Mask" "B.Paste")
			(net "P3V3_AUX_FPGA_VCCIO5")
		)
		(pad "2" smd circle
			(at -0.40005 0 180)
			(size 0 0)
			(layers "B.Cu" "B.Mask" "B.Paste")
			(net "GND")
		)
	)
)
